# Lightning_PTB_Pick & place.xlsx — Sheet1 (pick-and-place)
| 14629-1a.1120WZS1847.brd |  |  |  |  |  |  |  |  |
| Date  Thu Mar 09 15:22:08 2017 |  |  |  |  |  |  |  |  |
| Total Components:  61 |  |  |  |  |  |  |  |  |
| Component Report |  |  |  |  |  |  |  |  |
| REFDES | COMP_DEVICE_TYPE | COMP_VALUE | COMP_TOL | COMP_PACKAGE | SYM_X | SYM_Y | SYM_ROTATE | SYM_MIRROR |
| C344 | C603H36 | SCD1U50V3KX-GP | 78.10424.2BL | C603H36 | 458.07 | 3908.68 | 180 | NO |
| C345 | C402H22 | SCD01U50V2KX-1GP | 78.10324.2FL | C402H22 | 413.09 | 3892.63 | 180 | NO |
| C348 | C805H56 | SC10U25V5KX-GP | 78.10622.51L | C805H56 | 1.97 | 1936.19 | 180 | NO |
| C349 | C805H56 | SC10U25V5KX-GP | 78.10622.51L | C805H56 | 92.97 | 1936.19 | 180 | NO |
| C355 | C805H56 | SC10U25V5KX-GP | 78.10622.51L | C805H56 | 4728.9799999999996 | 1864.36 | 180 | NO |
| C357 | C603H36 | SC220P50V3JN-GP | 78.22134.1BL | C603H36 | 381.28 | 3771.32 | 180 | NO |
| C358 | C603H36 | SC220P50V3JN-GP | 78.22134.1BL | C603H36 | 381.09 | 3659.33 | 0 | NO |
| C359 | C603H36 | SC220P50V3JN-GP | 78.22134.1BL | C603H36 | 5425 | 2609.71 | 0 | NO |
| C360 | C603H36 | SC220P50V3JN-GP | 78.22134.1BL | C603H36 | 5425 | 2719.71 | 180 | NO |
| C361 | C1210H107 | SC47U16V0MX-GP | 78.47611.53L | C1210H107 | 4620 | 1865 | 180 | NO |
| C362 | C1210H107 | SC47U16V0MX-GP | 78.47611.53L | C1210H107 | 4485 | 1865 | 180 | NO |
| C363 | C1210H107 | SC47U16V0MX-GP | 78.47611.53L | C1210H107 | 4350 | 1865 | 180 | NO |
| C364 | C1210H107 | SC47U16V0MX-GP | 78.47611.53L | C1210H107 | 4215 | 1865 | 180 | NO |
| CN4 | 51939-689LF | FCI-CONN52-4R-GP | 20.81942.024 | 51939-689LF | 6007.09 | 2244.09 | 90 | NO |
| GF1 | GF-36P-24P | GF-36P-24P-GP | ZZ.GF001.891 | GF-36P-24P | -374.05 | 2934.22 | 270 | NO |
| H1 | HOLET827X355B355R158-S | HOLE | ZZ.0HOLE.XXX | HOLET827X355B355R158-S | 5183.46 | 4488.18 | 0 | NO |
| H2 | HTE9B9R355-R-766 | HOLE | ZZ.0HOLE.XXX | HTE9B9R355-R-766 | 301.57 | 4153.54 | 0 | NO |
| H3 | HTE9B9R355-R-766 | HOLE | ZZ.0HOLE.XXX | HTE9B9R355-R-766 | 301.57 | 610.23 | 0 | NO |
| H4 | HOLET827X355B355R158-S | HOLE | ZZ.0HOLE.XXX | HOLET827X355B355R158-S | 4986.6099999999997 | 236.22 | 0 | NO |
| LED1 | LED1608AKH26 | LED-G-203-GP | 83.00191.K70 | LED1608AKH26 | 6344.88 | 748.03 | 180 | NO |
| LED16 | LED3640AKH166 | LED-IR-1-GP | 75.00426.010 | LED3640AKH166 | 6128.35 | 3452.76 | 90 | NO |
| PR64 | R603H22 | 0R3J-0-U-GP | 63.00000.00L | R603H22 | 6177.98 | 4059.36 | 0 | NO |
| PR65 | R603H22 | 0R3J-0-U-GP | 63.00000.00L | R603H22 | 6127.98 | 4058.36 | 0 | NO |
| Q31 | SNR2N4036-UH166 | SENSOR-2P-GP-U | 75.00325.010 | SNR2N4036-UH166 | 6128.35 | 3889.76 | 90 | NO |
| Q33 | SOT23CBE2D4H44 | MMBT2222A-3-GP | 84.02222.V11 | SOT23CBE2D4H44 | 5290.36 | 3121.02 | 180 | NO |
| Q34 | SOT23DGS2D4H44 | 2N7002-11-GP | 84.27002.W31 | SOT23DGS2D4H44 | 5290.11 | 2970.07 | 180 | NO |
| R342 | R402H16 | 10KR2F-2-GP | 64.10025.6DL | R402H16 | 527.04999999999995 | 3540.95 | 180 | NO |
| R343 | R402H16 | 10KR2F-2-GP | 64.10025.6DL | R402H16 | 483.25 | 3541.5 | 180 | NO |
| R344 | R402H16 | 10KR2F-2-GP | 64.10025.6DL | R402H16 | 510.94 | 3890.25 | 0 | NO |
| R353 | R402H16 | 10KR2F-2-GP | 64.10025.6DL | R402H16 | 600.52 | 3889.92 | 0 | NO |
| R365 | R402H16 | 0R2J-2-GP | 63.R0034.1DL | R402H16 | 5318.36 | 3306.02 | 90 | NO |
| R366 | R402H16 | 0R2J-2-GP | 63.R0034.1DL | R402H16 | 5318.36 | 3349.02 | 270 | NO |
| R369 | R402H16 | 4K7R2J-2-GP | 63.47234.1DL | R402H16 | 573.98 | 3541.6 | 180 | NO |
| R370 | R402H16 | 4K7R2J-2-GP | 63.47234.1DL | R402H16 | 553.52 | 3890.74 | 0 | NO |
| R374 | R402H16 | 470KR2F-GP | 64.47035.6DL | R402H16 | 5319.36 | 3264.02 | 90 | NO |
| R375 | R402H14 | 100R2F-L1-GP-U | 64.10005.6DL | R402H14 | 5319.36 | 3221.02 | 90 | NO |
| R376 | R402H16 | 100KR2F-L1-GP | 64.10035.6DL | R402H16 | 5245 | 3260 | 90 | NO |
| R378 | R805H24 | 68R5J-GP | 63.68031.16L | R805H24 | 5504.98 | 3261.36 | 0 | NO |
| R379 | R402H16 | 10KR2F-2-GP | 64.10025.6DL | R402H16 | 5380 | 2950 | 0 | NO |
| R384 | R402H16 | 0R2J-2-GP | 63.R0034.1DL | R402H16 | 368.98 | 3334.36 | 90 | NO |
| R385 | R402H16 | 0R2J-2-GP | 63.R0034.1DL | R402H16 | 368.98 | 3379.36 | 90 | NO |
| R386 | R402H16 | 0R2J-2-GP | 63.R0034.1DL | R402H16 | 5360.33 | 2689.71 | 90 | NO |
| R387 | R402H16 | 0R2J-2-GP | 63.R0034.1DL | R402H16 | 5360.33 | 2639.71 | 90 | NO |
| R388 | R402H16 | 0R2J-2-GP | 63.R0034.1DL | R402H16 | 318.08 | 3741.32 | 90 | NO |
| R389 | R402H16 | 0R2J-2-GP | 63.R0034.1DL | R402H16 | 318.08 | 3689.32 | 90 | NO |
| R390 | R402H16 | 0R2J-2-GP | 63.R0034.1DL | R402H16 | 5460 | 4190 | 270 | NO |
| R391 | R402H16 | 0R2J-2-GP | 63.R0034.1DL | R402H16 | 5480 | 4310 | 0 | NO |
| R480 | R402H16 | 0R2J-2-GP | 63.R0034.1DL | R402H16 | 677.98 | 3694.7 | 90 | NO |
| R481 | R402H16 | 0R2J-2-GP | 63.R0034.1DL | R402H16 | 678.47 | 3739.79 | 90 | NO |
| R482 | R402H16 | 0R2J-2-GP | 63.R0034.1DL | R402H16 | 5245 | 3220 | 270 | NO |
| R483 | R603H22 | 2KR3F-L-GP | 64.20015.55L | R603H22 | 6180 | 745 | 0 | NO |
| R484 | R402H16 | 0R2J-2-GP | 63.R0034.1DL | R402H16 | 430.72 | 3675.47 | 0 | NO |
| R485 | R402H16 | 0R2J-2-GP | 63.R0034.1DL | R402H16 | 677.91 | 3651.63 | 270 | NO |
| R486 | R402H16 | 0R2J-2-GP | 63.R0034.1DL | R402H16 | 431.59 | 3755.85 | 0 | NO |
| R487 | R402H16 | 0R2J-2-GP | 63.R0034.1DL | R402H16 | 678.5 | 3782.36 | 90 | NO |
| SW1 | MS-B1PL-10 | SW-PUSH-3P-3-GP | 022.40008.0011 | MS-B1PL-10 | 5813.39 | 4330.71 | 0 | NO |
| TC3 | CT7343H79 | ST68U16VDM-1-GP | 77.26861.05L | CT7343H79 | 4876.25 | 1856.86 | 180 | NO |
| TC4 | CT7343H79 | ST68U16VDM-1-GP | 77.26861.05L | CT7343H79 | 5381.35 | 1857.77 | 180 | NO |
| TC5 | CT7343H79 | ST68U16VDM-1-GP | 77.26861.05L | CT7343H79 | 5129.8900000000003 | 1857.62 | 180 | NO |
| TP9 | TPAD32 | TPAD32-GP | ZZ.0TPAD.191 | TPAD32 | 674.08 | 3912.59 | 0 | NO |
| U51 | SSOIC8-2H44 | PCA9511ADP-T-GP | 71.P9511.00W | SSOIC8-2H44 | 537.41999999999996 | 3715.02 | 0 | NO |
